#ISCELL
  mstr_misc dns *
  *
#ISCELL
  pure_quanta quanta_title_block_c *
  *
#ISCELL
  pure_quanta_power universal_gnd *
  page333_i10
#CELL
  pure_quanta mosfet_nch_dual *
  page333_i100
#CELL
  pure_quanta q_res *
  page333_i101
#ISCELL
  pure_quanta_power universal_power *
  page333_i102
#ISCELL
  pure_quanta_power universal_gnd *
  page333_i103
#ISCELL
  pure_quanta_power universal_gnd *
  page333_i104
#CELL
  pure_quanta q_cap *
  page333_i105
#ISCELL
  standard offpage *
  page333_i106
#ISCELL
  pure_quanta_power universal_gnd *
  page333_i108
#CELL
  pure_quanta q_res *
  page333_i109
#ISCELL
  pure_quanta_power universal_gnd *
  page333_i11
#ISCELL
  pure_quanta_power universal_power *
  page333_i110
#CELL
  pure_quanta q_cap *
  page333_i111
#ISCELL
  pure_quanta_power universal_gnd *
  page333_i112
#ISCELL
  pure_quanta_power universal_gnd *
  page333_i113
#CELL
  pure_quanta q_cap *
  page333_i114
#ISCELL
  pure_quanta_power universal_gnd *
  page333_i115
#CELL
  pure_quanta q_cap *
  page333_i116
#CELL
  pure_quanta mosfet_nch_dual *
  page333_i117
#CELL
  pure_quanta mosfet_nch_dual *
  page333_i118
#CELL
  pure_quanta mosfet_nch_dual *
  page333_i119
#ISCELL
  pure_quanta_power universal_gnd *
  page333_i12
#CELL
  pure_quanta mosfet_nch_dual *
  page333_i120
#CELL
  pure_quanta mosfet_nch_dual *
  page333_i121
#CELL
  pure_quanta mosfet_nch_dual *
  page333_i122
#ISCELL
  pure_quanta_power universal_power *
  page333_i123
#ISCELL
  standard offpage *
  page333_i124
#CELL
  pure_quanta q_cap *
  page333_i125
#ISCELL
  pure_quanta_power universal_gnd *
  page333_i126
#ISCELL
  pure_quanta_power universal_power *
  page333_i128
#CELL
  pure_quanta q_res *
  page333_i129
#ISCELL
  pure_quanta_power universal_power *
  page333_i13
#ISCELL
  pure_quanta_power universal_gnd *
  page333_i130
#ISCELL
  pure_quanta_power universal_gnd *
  page333_i131
#ISCELL
  pure_quanta_power universal_power *
  page333_i132
#CELL
  pure_quanta q_res *
  page333_i134
#ISCELL
  pure_quanta_power universal_gnd *
  page333_i135
#ISCELL
  standard offpage *
  page333_i136
#ISCELL
  standard offpage *
  page333_i137
#ISCELL
  pure_quanta_power universal_gnd *
  page333_i138
#CELL
  pure_quanta q_res *
  page333_i139
#CELL
  pure_quanta q_res *
  page333_i14
#ISCELL
  pure_quanta_power universal_power *
  page333_i141
#ISCELL
  pure_quanta_power universal_gnd *
  page333_i142
#ISCELL
  pure_quanta_power universal_gnd *
  page333_i143
#CELL
  pure_quanta q_res *
  page333_i144
#ISCELL
  pure_quanta_power universal_power *
  page333_i145
#ISCELL
  pure_quanta_power universal_gnd *
  page333_i147
#CELL
  pure_quanta q_cap *
  page333_i148
#ISCELL
  standard offpage *
  page333_i149
#ISCELL
  pure_quanta_power universal_power *
  page333_i150
#CELL
  pure_quanta mosfet_nch_dual *
  page333_i151
#CELL
  pure_quanta mosfet_nch_dual *
  page333_i152
#ISCELL
  pure_quanta_power universal_power *
  page333_i153
#CELL
  pure_quanta mosfet_nch_dual *
  page333_i154
#ISCELL
  standard offpage *
  page333_i155
#CELL
  pure_quanta q_cap *
  page333_i156
#ISCELL
  pure_quanta_power universal_gnd *
  page333_i157
#CELL
  pure_quanta q_res *
  page333_i158
#CELL
  pure_quanta mosfet_nch_dual *
  page333_i159
#ISCELL
  pure_quanta_power universal_power *
  page333_i16
#ISCELL
  pure_quanta_power universal_gnd *
  page333_i160
#ISCELL
  pure_quanta_power universal_power *
  page333_i161
#CELL
  pure_quanta q_res *
  page333_i162
#ISCELL
  pure_quanta_power universal_gnd *
  page333_i163
#ISCELL
  pure_quanta_power universal_power *
  page333_i164
#ISCELL
  pure_quanta_power universal_gnd *
  page333_i167
#ISCELL
  standard offpage *
  page333_i168
#ISCELL
  standard offpage *
  page333_i169
#CELL
  pure_quanta q_res *
  page333_i171
#CELL
  pure_quanta q_res *
  page333_i172
#CELL
  pure_quanta q_res *
  page333_i173
#CELL
  pure_quanta q_res *
  page333_i174
#CELL
  pure_quanta q_res *
  page333_i175
#CELL
  pure_quanta q_res *
  page333_i176
#CELL
  pure_quanta q_res *
  page333_i177
#CELL
  pure_quanta q_res *
  page333_i178
#CELL
  pure_quanta q_res *
  page333_i179
#CELL
  pure_quanta q_res *
  page333_i18
#CELL
  pure_quanta q_res *
  page333_i180
#CELL
  pure_quanta q_res *
  page333_i19
#ISCELL
  pure_quanta_power universal_power *
  page333_i21
#ISCELL
  standard offpage *
  page333_i22
#ISCELL
  pure_quanta_power universal_gnd *
  page333_i23
#CELL
  pure_quanta q_res *
  page333_i24
#ISCELL
  pure_quanta_power universal_power *
  page333_i25
#ISCELL
  standard offpage *
  page333_i28
#ISCELL
  pure_quanta_power universal_gnd *
  page333_i29
#CELL
  pure_quanta q_res *
  page333_i30
#ISCELL
  pure_quanta_power universal_power *
  page333_i31
#CELL
  pure_quanta mosfet_nch_dual *
  page333_i33
#CELL
  pure_quanta mosfet_nch_dual *
  page333_i35
#CELL
  pure_quanta mosfet_nch_dual *
  page333_i37
#ISCELL
  pure_quanta_power universal_power *
  page333_i46
#ISCELL
  pure_quanta_power universal_power *
  page333_i47
#ISCELL
  pure_quanta_power universal_power *
  page333_i49
#ISCELL
  pure_quanta_power universal_power *
  page333_i51
#ISCELL
  pure_quanta_power universal_power *
  page333_i53
#ISCELL
  pure_quanta_power universal_gnd *
  page333_i55
#CELL
  pure_quanta q_res *
  page333_i56
#ISCELL
  pure_quanta_power universal_gnd *
  page333_i57
#CELL
  pure_quanta q_res *
  page333_i58
#ISCELL
  pure_quanta_power universal_gnd *
  page333_i59
#ISCELL
  standard offpage *
  page333_i6
#CELL
  pure_quanta q_res *
  page333_i60
#ISCELL
  pure_quanta_power universal_gnd *
  page333_i61
#CELL
  pure_quanta q_res *
  page333_i62
#ISCELL
  pure_quanta_power universal_gnd *
  page333_i63
#CELL
  pure_quanta q_res *
  page333_i66
#CELL
  pure_quanta q_res *
  page333_i67
#CELL
  pure_quanta q_res *
  page333_i68
#ISCELL
  standard offpage *
  page333_i7
#ISCELL
  standard offpage *
  page333_i8
#CELL
  pure_quanta q_res *
  page333_i80
#CELL
  pure_quanta mosfet_nch_dual *
  page333_i82
#ISCELL
  pure_quanta_power universal_gnd *
  page333_i83
#ISCELL
  pure_quanta_power universal_power *
  page333_i85
#ISCELL
  standard offpage *
  page333_i86
#ISCELL
  standard offpage *
  page333_i87
#CELL
  pure_quanta mosfet_nch_dual *
  page333_i88
#ISCELL
  pure_quanta_power universal_gnd *
  page333_i89
#ISCELL
  pure_quanta_power universal_power *
  page333_i90
#CELL
  pure_quanta q_res *
  page333_i91
#CELL
  pure_quanta q_cap *
  page333_i92
#ISCELL
  pure_quanta_power universal_gnd *
  page333_i93
#ISCELL
  standard offpage *
  page333_i94
#ISCELL
  pure_quanta_power universal_gnd *
  page333_i96
#ISCELL
  pure_quanta_power universal_power *
  page333_i98
#ISCELL
  standard offpage *
  page333_i99
